(kicad_pcb
	(version 20260206)
	(generator "pcbnew")
	(generator_version "10.0")
	(general
		(thickness 1.6)
		(legacy_teardrops no)
	)
	(paper "A4")
	(title_block
		(title "baseboard — 13948-1b.1110WZS1818.brd")
		(comment 1 "Honey Badger (Wiwynn) / footprint 852 of 2523 (SU2), pads 1-122 of 896")
	)
	(layers
		(0 "F.Cu" signal "TOP")
		(4 "In1.Cu" signal "L2GND")
		(6 "In2.Cu" signal "L3")
		(8 "In3.Cu" signal "L4VCC")
		(10 "In4.Cu" signal "L5VCC")
		(12 "In5.Cu" signal "L6")
		(14 "In6.Cu" signal "L7GND")
		(2 "B.Cu" signal "BOTTOM")
		(9 "F.Adhes" user "F.Adhesive")
		(11 "B.Adhes" user "B.Adhesive")
		(13 "F.Paste" user "Package Geometry/Pastemask Top")
		(15 "B.Paste" user "Package Geometry/Pastemask Bottom")
		(5 "F.SilkS" user "Ref Des/Silkscreen Top")
		(7 "B.SilkS" user "Ref Des/Silkscreen Bottom")
		(1 "F.Mask" user "Board Geometry/Soldermask Top")
		(3 "B.Mask" user "Board Geometry/Soldermask Bottom")
		(17 "Dwgs.User" user "User.Drawings")
		(19 "Cmts.User" user "User.Comments")
		(21 "Eco1.User" user "User.Eco1")
		(23 "Eco2.User" user "User.Eco2")
		(25 "Edge.Cuts" user "Board Geometry/Outline")
		(27 "Margin" user)
		(31 "F.CrtYd" user "Package Geometry/Place Bound Top")
		(29 "B.CrtYd" user "Package Geometry/Place Bound Bottom")
		(35 "F.Fab" user "Ref Des/Assembly Top")
		(33 "B.Fab" user "Ref Des/Assembly Bottom")
	)
	(footprint ""
		(layer "F.Cu")
		(at 102.350062 -44.99991)
		(property "Reference" "SU2"
			(at 0 0 0)
			(layer "F.SilkS")
			(hide yes)
			(effects
				(font
					(size 1.27 1.27)
				)
			)
		)
		(property "Value" "SAS3008C0-1-DB-500020657-1-GP"
			(at -20.374102 -5.0292 0)
			(unlocked yes)
			(layer "F.Fab")
			(hide yes)
			(effects
				(font
					(size 1.016 1.016)
					(thickness 0.1524)
				)
			)
		)
		(property "Device Type" "BGA896D25H78"
			(at -20.374102 -6.5532 0)
			(unlocked yes)
			(layer "F.Fab")
			(hide yes)
			(effects
				(font
					(size 1.016 1.016)
					(thickness 0.1524)
				)
			)
		)
		(duplicate_pad_numbers_are_jumpers no)
		(pad "A2" smd circle
			(at -10.80008 -11.599926)
			(size 0.4064 0.4064)
			(layers "F.Cu" "F.Mask" "F.Paste")
			(net "Net_1034")
		)
		(pad "A3" smd circle
			(at -9.99998 -11.599926)
			(size 0.4064 0.4064)
			(layers "F.Cu" "F.Mask" "F.Paste")
			(net "Net_1035")
		)
		(pad "A4" smd circle
			(at -9.19988 -11.599926)
			(size 0.3556 0.3556)
			(layers "F.Cu" "F.Mask" "F.Paste")
			(net "GND")
		)
		(pad "A5" smd circle
			(at -8.400034 -11.599926)
			(size 0.3556 0.3556)
			(layers "F.Cu" "F.Mask" "F.Paste")
			(net "Net_1036")
		)
		(pad "A6" smd circle
			(at -7.599934 -11.599926)
			(size 0.3556 0.3556)
			(layers "F.Cu" "F.Mask" "F.Paste")
			(net "ICE1_TMS")
		)
		(pad "A7" smd circle
			(at -6.800088 -11.599926)
			(size 0.3556 0.3556)
			(layers "F.Cu" "F.Mask" "F.Paste")
			(net "Net_1037")
		)
		(pad "A8" smd circle
			(at -5.999988 -11.599926)
			(size 0.3556 0.3556)
			(layers "F.Cu" "F.Mask" "F.Paste")
			(net "ICE0_TRST#")
		)
		(pad "A9" smd circle
			(at -5.199888 -11.599926)
			(size 0.3556 0.3556)
			(layers "F.Cu" "F.Mask" "F.Paste")
			(net "ICE0_TCK")
		)
		(pad "A10" smd circle
			(at -4.400042 -11.599926)
			(size 0.3556 0.3556)
			(layers "F.Cu" "F.Mask" "F.Paste")
			(net "ICE1_TDO")
		)
		(pad "A11" smd circle
			(at -3.599942 -11.599926)
			(size 0.3556 0.3556)
			(layers "F.Cu" "F.Mask" "F.Paste")
			(net "GND")
		)
		(pad "A12" smd circle
			(at -2.800096 -11.599926)
			(size 0.3556 0.3556)
			(layers "F.Cu" "F.Mask" "F.Paste")
			(net "Net_1027")
		)
		(pad "A13" smd circle
			(at -1.999996 -11.599926)
			(size 0.3556 0.3556)
			(layers "F.Cu" "F.Mask" "F.Paste")
			(net "PWRGD_P0V955_C")
		)
		(pad "A14" smd circle
			(at -1.199896 -11.599926)
			(size 0.3556 0.3556)
			(layers "F.Cu" "F.Mask" "F.Paste")
			(net "HM40ADC_VDDA")
		)
		(pad "A15" smd circle
			(at -0.40005 -11.599926)
			(size 0.3556 0.3556)
			(layers "F.Cu" "F.Mask" "F.Paste")
			(net "GND")
		)
		(pad "A16" smd circle
			(at 0.40005 -11.599926)
			(size 0.3556 0.3556)
			(layers "F.Cu" "F.Mask" "F.Paste")
			(net "IOC_TRST_N")
		)
		(pad "A17" smd circle
			(at 1.199896 -11.599926)
			(size 0.3556 0.3556)
			(layers "F.Cu" "F.Mask" "F.Paste")
			(net "JTAG_IOC_TDI")
		)
		(pad "A18" smd circle
			(at 1.999996 -11.599926)
			(size 0.3556 0.3556)
			(layers "F.Cu" "F.Mask" "F.Paste")
			(net "LSI_IDDT")
		)
		(pad "A19" smd circle
			(at 2.800096 -11.599926)
			(size 0.3556 0.3556)
			(layers "F.Cu" "F.Mask" "F.Paste")
			(net "Net_1028")
		)
		(pad "A20" smd circle
			(at 3.599942 -11.599926)
			(size 0.3556 0.3556)
			(layers "F.Cu" "F.Mask" "F.Paste")
			(net "Net_1029")
		)
		(pad "A21" smd circle
			(at 4.400042 -11.599926)
			(size 0.3556 0.3556)
			(layers "F.Cu" "F.Mask" "F.Paste")
			(net "XM_NOR_CS_N")
		)
		(pad "A22" smd circle
			(at 5.199888 -11.599926)
			(size 0.3556 0.3556)
			(layers "F.Cu" "F.Mask" "F.Paste")
			(net "XM_RB")
		)
		(pad "A23" smd circle
			(at 5.999988 -11.599926)
			(size 0.3556 0.3556)
			(layers "F.Cu" "F.Mask" "F.Paste")
			(net "Net_1023")
		)
		(pad "A24" smd circle
			(at 6.800088 -11.599926)
			(size 0.3556 0.3556)
			(layers "F.Cu" "F.Mask" "F.Paste")
			(net "XM_WE_N")
		)
		(pad "A25" smd circle
			(at 7.599934 -11.599926)
			(size 0.3556 0.3556)
			(layers "F.Cu" "F.Mask" "F.Paste")
			(net "XM_WP")
		)
		(pad "A26" smd circle
			(at 8.400034 -11.599926)
			(size 0.3556 0.3556)
			(layers "F.Cu" "F.Mask" "F.Paste")
			(net "XM_ADDR_3")
		)
		(pad "A27" smd circle
			(at 9.19988 -11.599926)
			(size 0.3556 0.3556)
			(layers "F.Cu" "F.Mask" "F.Paste")
			(net "Net_1024")
		)
		(pad "A28" smd circle
			(at 9.99998 -11.599926)
			(size 0.4064 0.4064)
			(layers "F.Cu" "F.Mask" "F.Paste")
			(net "XM_ADDR_4")
		)
		(pad "A29" smd circle
			(at 10.80008 -11.599926)
			(size 0.4064 0.4064)
			(layers "F.Cu" "F.Mask" "F.Paste")
			(net "XM_DATA_11")
		)
		(pad "AA1" smd circle
			(at -11.599926 4.400042)
			(size 0.3556 0.3556)
			(layers "F.Cu" "F.Mask" "F.Paste")
			(net "SAS3008_RAID_TX_C_P6")
		)
		(pad "AA2" smd circle
			(at -10.80008 4.400042)
			(size 0.3556 0.3556)
			(layers "F.Cu" "F.Mask" "F.Paste")
			(net "SAS3008_RAID_TX_C_N6")
		)
		(pad "AA3" smd circle
			(at -9.99998 4.400042)
			(size 0.3556 0.3556)
			(layers "F.Cu" "F.Mask" "F.Paste")
			(net "GND")
		)
		(pad "AA4" smd circle
			(at -9.19988 4.400042)
			(size 0.3556 0.3556)
			(layers "F.Cu" "F.Mask" "F.Paste")
			(net "IOC_SAS_RX_P6")
		)
		(pad "AA5" smd circle
			(at -8.400034 4.400042)
			(size 0.3556 0.3556)
			(layers "F.Cu" "F.Mask" "F.Paste")
			(net "IOC_SAS_RX_N6")
		)
		(pad "AA6" smd circle
			(at -7.599934 4.400042)
			(size 0.3556 0.3556)
			(layers "F.Cu" "F.Mask" "F.Paste")
			(net "GND")
		)
		(pad "AA7" smd circle
			(at -6.800088 4.400042)
			(size 0.3556 0.3556)
			(layers "F.Cu" "F.Mask" "F.Paste")
			(net "GND")
		)
		(pad "AA8" smd circle
			(at -5.999988 4.400042)
			(size 0.3556 0.3556)
			(layers "F.Cu" "F.Mask" "F.Paste")
			(net "GND")
		)
		(pad "AA9" smd circle
			(at -5.199888 4.400042)
			(size 0.3556 0.3556)
			(layers "F.Cu" "F.Mask" "F.Paste")
			(net "GND")
		)
		(pad "AA10" smd circle
			(at -4.400042 4.400042)
			(size 0.3556 0.3556)
			(layers "F.Cu" "F.Mask" "F.Paste")
			(net "GND")
		)
		(pad "AA11" smd circle
			(at -3.599942 4.400042)
			(size 0.3556 0.3556)
			(layers "F.Cu" "F.Mask" "F.Paste")
			(net "GND")
		)
		(pad "AA12" smd circle
			(at -2.800096 4.400042)
			(size 0.3556 0.3556)
			(layers "F.Cu" "F.Mask" "F.Paste")
			(net "GND")
		)
		(pad "AA13" smd circle
			(at -1.999996 4.400042)
			(size 0.3556 0.3556)
			(layers "F.Cu" "F.Mask" "F.Paste")
			(net "GND")
		)
		(pad "AA14" smd circle
			(at -1.199896 4.400042)
			(size 0.3556 0.3556)
			(layers "F.Cu" "F.Mask" "F.Paste")
			(net "GND")
		)
		(pad "AA15" smd circle
			(at -0.40005 4.400042)
			(size 0.3556 0.3556)
			(layers "F.Cu" "F.Mask" "F.Paste")
			(net "GND")
		)
		(pad "AA16" smd circle
			(at 0.40005 4.400042)
			(size 0.3556 0.3556)
			(layers "F.Cu" "F.Mask" "F.Paste")
			(net "GND")
		)
		(pad "AA17" smd circle
			(at 1.199896 4.400042)
			(size 0.3556 0.3556)
			(layers "F.Cu" "F.Mask" "F.Paste")
			(net "GND")
		)
		(pad "AA18" smd circle
			(at 1.999996 4.400042)
			(size 0.3556 0.3556)
			(layers "F.Cu" "F.Mask" "F.Paste")
			(net "GND")
		)
		(pad "AA19" smd circle
			(at 2.800096 4.400042)
			(size 0.3556 0.3556)
			(layers "F.Cu" "F.Mask" "F.Paste")
			(net "GND")
		)
		(pad "AA20" smd circle
			(at 3.599942 4.400042)
			(size 0.3556 0.3556)
			(layers "F.Cu" "F.Mask" "F.Paste")
			(net "GND")
		)
		(pad "AA21" smd circle
			(at 4.400042 4.400042)
			(size 0.3556 0.3556)
			(layers "F.Cu" "F.Mask" "F.Paste")
			(net "GND")
		)
		(pad "AA22" smd circle
			(at 5.199888 4.400042)
			(size 0.3556 0.3556)
			(layers "F.Cu" "F.Mask" "F.Paste")
			(net "GND")
		)
		(pad "AA23" smd circle
			(at 5.999988 4.400042)
			(size 0.3556 0.3556)
			(layers "F.Cu" "F.Mask" "F.Paste")
			(net "PLL_VDD")
		)
		(pad "AA24" smd circle
			(at 6.800088 4.400042)
			(size 0.3556 0.3556)
			(layers "F.Cu" "F.Mask" "F.Paste")
			(net "GND")
		)
		(pad "AA25" smd circle
			(at 7.599934 4.400042)
			(size 0.3556 0.3556)
			(layers "F.Cu" "F.Mask" "F.Paste")
			(net "GND")
		)
		(pad "AA26" smd circle
			(at 8.400034 4.400042)
			(size 0.3556 0.3556)
			(layers "F.Cu" "F.Mask" "F.Paste")
			(net "GND")
		)
		(pad "AA27" smd circle
			(at 9.19988 4.400042)
			(size 0.3556 0.3556)
			(layers "F.Cu" "F.Mask" "F.Paste")
			(net "P1V8_C")
		)
		(pad "AA28" smd circle
			(at 9.99998 4.400042)
			(size 0.3556 0.3556)
			(layers "F.Cu" "F.Mask" "F.Paste")
			(net "IOC_GPIO_36")
		)
		(pad "AA29" smd circle
			(at 10.80008 4.400042)
			(size 0.3556 0.3556)
			(layers "F.Cu" "F.Mask" "F.Paste")
			(net "IOC_GPIO_33")
		)
		(pad "AA30" smd circle
			(at 11.599926 4.400042)
			(size 0.3556 0.3556)
			(layers "F.Cu" "F.Mask" "F.Paste")
			(net "IOC_GPIO_37")
		)
		(pad "AB1" smd circle
			(at -11.599926 5.199888)
			(size 0.3556 0.3556)
			(layers "F.Cu" "F.Mask" "F.Paste")
			(net "SAS3008_RAID_TX_C_P7")
		)
		(pad "AB2" smd circle
			(at -10.80008 5.199888)
			(size 0.3556 0.3556)
			(layers "F.Cu" "F.Mask" "F.Paste")
			(net "SAS3008_RAID_TX_C_N7")
		)
		(pad "AB3" smd circle
			(at -9.99998 5.199888)
			(size 0.3556 0.3556)
			(layers "F.Cu" "F.Mask" "F.Paste")
			(net "GND")
		)
		(pad "AB4" smd circle
			(at -9.19988 5.199888)
			(size 0.3556 0.3556)
			(layers "F.Cu" "F.Mask" "F.Paste")
			(net "IOC_SAS_RX_P7")
		)
		(pad "AB5" smd circle
			(at -8.400034 5.199888)
			(size 0.3556 0.3556)
			(layers "F.Cu" "F.Mask" "F.Paste")
			(net "IOC_SAS_RX_N7")
		)
		(pad "AB6" smd circle
			(at -7.599934 5.199888)
			(size 0.3556 0.3556)
			(layers "F.Cu" "F.Mask" "F.Paste")
			(net "GND")
		)
		(pad "AB7" smd circle
			(at -6.800088 5.199888)
			(size 0.3556 0.3556)
			(layers "F.Cu" "F.Mask" "F.Paste")
			(net "SAS0_AVDD")
		)
		(pad "AB8" smd circle
			(at -5.999988 5.199888)
			(size 0.3556 0.3556)
			(layers "F.Cu" "F.Mask" "F.Paste")
			(net "GND")
		)
		(pad "AB9" smd circle
			(at -5.199888 5.199888)
			(size 0.3556 0.3556)
			(layers "F.Cu" "F.Mask" "F.Paste")
			(net "GND")
		)
		(pad "AB10" smd circle
			(at -4.400042 5.199888)
			(size 0.3556 0.3556)
			(layers "F.Cu" "F.Mask" "F.Paste")
			(net "GND")
		)
		(pad "AB11" smd circle
			(at -3.599942 5.199888)
			(size 0.3556 0.3556)
			(layers "F.Cu" "F.Mask" "F.Paste")
			(net "GND")
		)
		(pad "AB12" smd circle
			(at -2.800096 5.199888)
			(size 0.3556 0.3556)
			(layers "F.Cu" "F.Mask" "F.Paste")
			(net "GND")
		)
		(pad "AB13" smd circle
			(at -1.999996 5.199888)
			(size 0.3556 0.3556)
			(layers "F.Cu" "F.Mask" "F.Paste")
			(net "GND")
		)
		(pad "AB14" smd circle
			(at -1.199896 5.199888)
			(size 0.3556 0.3556)
			(layers "F.Cu" "F.Mask" "F.Paste")
			(net "GND")
		)
		(pad "AB15" smd circle
			(at -0.40005 5.199888)
			(size 0.3556 0.3556)
			(layers "F.Cu" "F.Mask" "F.Paste")
			(net "GND")
		)
		(pad "AB16" smd circle
			(at 0.40005 5.199888)
			(size 0.3556 0.3556)
			(layers "F.Cu" "F.Mask" "F.Paste")
			(net "GND")
		)
		(pad "AB17" smd circle
			(at 1.199896 5.199888)
			(size 0.3556 0.3556)
			(layers "F.Cu" "F.Mask" "F.Paste")
			(net "GND")
		)
		(pad "AB18" smd circle
			(at 1.999996 5.199888)
			(size 0.3556 0.3556)
			(layers "F.Cu" "F.Mask" "F.Paste")
			(net "GND")
		)
		(pad "AB19" smd circle
			(at 2.800096 5.199888)
			(size 0.3556 0.3556)
			(layers "F.Cu" "F.Mask" "F.Paste")
			(net "GND")
		)
		(pad "AB20" smd circle
			(at 3.599942 5.199888)
			(size 0.3556 0.3556)
			(layers "F.Cu" "F.Mask" "F.Paste")
			(net "GND")
		)
		(pad "AB21" smd circle
			(at 4.400042 5.199888)
			(size 0.3556 0.3556)
			(layers "F.Cu" "F.Mask" "F.Paste")
			(net "GND")
		)
		(pad "AB22" smd circle
			(at 5.199888 5.199888)
			(size 0.3556 0.3556)
			(layers "F.Cu" "F.Mask" "F.Paste")
			(net "GND")
		)
		(pad "AB23" smd circle
			(at 5.999988 5.199888)
			(size 0.3556 0.3556)
			(layers "F.Cu" "F.Mask" "F.Paste")
			(net "GND")
		)
		(pad "AB24" smd circle
			(at 6.800088 5.199888)
			(size 0.3556 0.3556)
			(layers "F.Cu" "F.Mask" "F.Paste")
			(net "GND")
		)
		(pad "AB25" smd circle
			(at 7.599934 5.199888)
			(size 0.3556 0.3556)
			(layers "F.Cu" "F.Mask" "F.Paste")
			(net "GND")
		)
		(pad "AB26" smd circle
			(at 8.400034 5.199888)
			(size 0.3556 0.3556)
			(layers "F.Cu" "F.Mask" "F.Paste")
			(net "P1V8_C")
		)
		(pad "AB27" smd circle
			(at 9.19988 5.199888)
			(size 0.3556 0.3556)
			(layers "F.Cu" "F.Mask" "F.Paste")
			(net "GND")
		)
		(pad "AB28" smd circle
			(at 9.99998 5.199888)
			(size 0.3556 0.3556)
			(layers "F.Cu" "F.Mask" "F.Paste")
			(net "IOC_GPIO_34")
		)
		(pad "AB29" smd circle
			(at 10.80008 5.199888)
			(size 0.3556 0.3556)
			(layers "F.Cu" "F.Mask" "F.Paste")
			(net "IOC_GPIO_23")
		)
		(pad "AB30" smd circle
			(at 11.599926 5.199888)
			(size 0.3556 0.3556)
			(layers "F.Cu" "F.Mask" "F.Paste")
			(net "IOC_GPIO_35")
		)
		(pad "AC1" smd circle
			(at -11.599926 5.999988)
			(size 0.3556 0.3556)
			(layers "F.Cu" "F.Mask" "F.Paste")
			(net "SAS0_VDDH")
		)
		(pad "AC2" smd circle
			(at -10.80008 5.999988)
			(size 0.3556 0.3556)
			(layers "F.Cu" "F.Mask" "F.Paste")
			(net "GND")
		)
		(pad "AC3" smd circle
			(at -9.99998 5.999988)
			(size 0.3556 0.3556)
			(layers "F.Cu" "F.Mask" "F.Paste")
			(net "GND")
		)
		(pad "AC4" smd circle
			(at -9.19988 5.999988)
			(size 0.3556 0.3556)
			(layers "F.Cu" "F.Mask" "F.Paste")
			(net "SAS0_AVDD")
		)
		(pad "AC5" smd circle
			(at -8.400034 5.999988)
			(size 0.3556 0.3556)
			(layers "F.Cu" "F.Mask" "F.Paste")
			(net "GND")
		)
		(pad "AC6" smd circle
			(at -7.599934 5.999988)
			(size 0.3556 0.3556)
			(layers "F.Cu" "F.Mask" "F.Paste")
			(net "SAS0_VDDH")
		)
		(pad "AC7" smd circle
			(at -6.800088 5.999988)
			(size 0.3556 0.3556)
			(layers "F.Cu" "F.Mask" "F.Paste")
			(net "GND")
		)
		(pad "AC8" smd circle
			(at -5.999988 5.999988)
			(size 0.3556 0.3556)
			(layers "F.Cu" "F.Mask" "F.Paste")
			(net "GND")
		)
		(pad "AC9" smd circle
			(at -5.199888 5.999988)
			(size 0.3556 0.3556)
			(layers "F.Cu" "F.Mask" "F.Paste")
			(net "GND")
		)
		(pad "AC10" smd circle
			(at -4.400042 5.999988)
			(size 0.3556 0.3556)
			(layers "F.Cu" "F.Mask" "F.Paste")
			(net "GND")
		)
		(pad "AC11" smd circle
			(at -3.599942 5.999988)
			(size 0.3556 0.3556)
			(layers "F.Cu" "F.Mask" "F.Paste")
			(net "PCE_AVDD")
		)
		(pad "AC12" smd circle
			(at -2.800096 5.999988)
			(size 0.3556 0.3556)
			(layers "F.Cu" "F.Mask" "F.Paste")
			(net "GND")
		)
		(pad "AC13" smd circle
			(at -1.999996 5.999988)
			(size 0.3556 0.3556)
			(layers "F.Cu" "F.Mask" "F.Paste")
			(net "GND")
		)
		(pad "AC14" smd circle
			(at -1.199896 5.999988)
			(size 0.3556 0.3556)
			(layers "F.Cu" "F.Mask" "F.Paste")
			(net "GND")
		)
		(pad "AC15" smd circle
			(at -0.40005 5.999988)
			(size 0.3556 0.3556)
			(layers "F.Cu" "F.Mask" "F.Paste")
			(net "GND")
		)
		(pad "AC16" smd circle
			(at 0.40005 5.999988)
			(size 0.3556 0.3556)
			(layers "F.Cu" "F.Mask" "F.Paste")
			(net "GND")
		)
		(pad "AC17" smd circle
			(at 1.199896 5.999988)
			(size 0.3556 0.3556)
			(layers "F.Cu" "F.Mask" "F.Paste")
			(net "GND")
		)
		(pad "AC18" smd circle
			(at 1.999996 5.999988)
			(size 0.3556 0.3556)
			(layers "F.Cu" "F.Mask" "F.Paste")
			(net "GND")
		)
		(pad "AC19" smd circle
			(at 2.800096 5.999988)
			(size 0.3556 0.3556)
			(layers "F.Cu" "F.Mask" "F.Paste")
			(net "GND")
		)
		(pad "AC20" smd circle
			(at 3.599942 5.999988)
			(size 0.3556 0.3556)
			(layers "F.Cu" "F.Mask" "F.Paste")
			(net "GND")
		)
		(pad "AC21" smd circle
			(at 4.400042 5.999988)
			(size 0.3556 0.3556)
			(layers "F.Cu" "F.Mask" "F.Paste")
			(net "GND")
		)
		(pad "AC22" smd circle
			(at 5.199888 5.999988)
			(size 0.3556 0.3556)
			(layers "F.Cu" "F.Mask" "F.Paste")
			(net "GND")
		)
		(pad "AC23" smd circle
			(at 5.999988 5.999988)
			(size 0.3556 0.3556)
			(layers "F.Cu" "F.Mask" "F.Paste")
			(net "GND")
		)
		(pad "AC24" smd circle
			(at 6.800088 5.999988)
			(size 0.3556 0.3556)
			(layers "F.Cu" "F.Mask" "F.Paste")
			(net "GND")
		)
		(pad "AC25" smd circle
			(at 7.599934 5.999988)
			(size 0.3556 0.3556)
			(layers "F.Cu" "F.Mask" "F.Paste")
			(net "GND")
		)
		(pad "AC26" smd circle
			(at 8.400034 5.999988)
			(size 0.3556 0.3556)
			(layers "F.Cu" "F.Mask" "F.Paste")
			(net "GND")
		)
		(pad "AC27" smd circle
			(at 9.19988 5.999988)
			(size 0.3556 0.3556)
			(layers "F.Cu" "F.Mask" "F.Paste")
			(net "P1V8_C")
		)
		(pad "AC28" smd circle
			(at 9.99998 5.999988)
			(size 0.3556 0.3556)
			(layers "F.Cu" "F.Mask" "F.Paste")
			(net "IOC_GPIO_28")
		)
		(pad "AC29" smd circle
			(at 10.80008 5.999988)
			(size 0.3556 0.3556)
			(layers "F.Cu" "F.Mask" "F.Paste")
			(net "IOC_GPIO_30")
		)
		(pad "AC30" smd circle
			(at 11.599926 5.999988)
			(size 0.3556 0.3556)
			(layers "F.Cu" "F.Mask" "F.Paste")
			(net "IOC_GPIO_8")
		)
		(pad "AD1" smd circle
			(at -11.599926 6.800088)
			(size 0.3556 0.3556)
			(layers "F.Cu" "F.Mask" "F.Paste")
			(net "SAS3008_RAID_TX_C_P3")
		)
		(pad "AD2" smd circle
			(at -10.80008 6.800088)
			(size 0.3556 0.3556)
			(layers "F.Cu" "F.Mask" "F.Paste")
			(net "SAS3008_RAID_TX_C_N3")
		)
		(pad "AD3" smd circle
			(at -9.99998 6.800088)
			(size 0.3556 0.3556)
			(layers "F.Cu" "F.Mask" "F.Paste")
			(net "GND")
		)
		(pad "AD4" smd circle
			(at -9.19988 6.800088)
			(size 0.3556 0.3556)
			(layers "F.Cu" "F.Mask" "F.Paste")
			(net "3008_SAS_RX_P3")
		)
	)
)
